FILE_TYPE = CONNECTIVITY;
{Allegro Design Entry HDL 16.6-p007 (v16-6-112F) 10/10/2012}
"PAGE_NUMBER" = 168;
0"NC";
1"GND\g";
2"P3V3_STBY\g";
3"GND\g";
4"P3V3_STBY\g";
5"GND\g";
6"P3V3_STBY\g";
7"GND\g";
8"FM_UART_SWITCH_N";
9"FM_UART_SEL_N";
10"FM_SOL_UART_CH_SEL";
11"FM_DB_PRESENT";
12"FM_DB_UART_SEL4_N";
13"FM_DB_UART_SEL3_N";
14"FM_POST_CARD_PRES_BMC_N";
15"FM_DB_UART_SEL1_N";
16"FM_DB_UART_SEL2_N";
17"FM_DB_UART_SEL0_N";
18"TP_FET_Q56_3";
19"TP_FET_Q56_4";
20"DEBUG_CARD2_PRSNT";
%"RES"
"2","(-3400,3050)","0","mstr_discrete","I11";
;
CDS_SEC"1"
LOCATION"R1L36"
VALUE"1.00K"
TOLERANCE"1%"
MATERIAL"CHIP"
WATTAGE"1/16W"
PART_NUMBER"G21796-026"
PACK_TYPE"0402"
SEC_TYPE"0402"
CDS_LIB"mstr_discrete"
BOM_COST"DEBUG"
SEC"1"
CDS_LOCATION"R1L36"
ROOM"UART_MUX";
"A"
$PN"1"4;
"B"
$PN"2"11;
%"GND"
"1","(-3400,2525)","0","mstr_symbols","I14";
;
HDL_POWER"GND"
BODY_TYPE"PLUMBING"
VOLTAGE"0.0V"
SIZE"1B"
CDS_LIB"mstr_symbols";
"A\NAC"1;
%"FET_N_DUAL"
"5","(-1525,4425)","0","mstr_discrete","I18";
;
CDS_SEC"2"
LOCATION"Q1L4"
PART_NUMBER"D24280-001"
VALUE"2N7002DW"
MATERIAL"FET"
PACK_TYPE"SMLF"
BOM_COST"DEBUG"
CDS_LIB"mstr_discrete"
SEC_TYPE"SMLF"
SEC"2"
CDS_LOCATION"Q1L4"
ROOM"UART_MUX";
"GATE <SIZE -1..0>"
$PN"5"19;
"SOURCE <SIZE-1..0>"
$PN"4"19;
"DRAIN <SIZE -1..0>"
$PN"3"18;
%"FET_N_DUAL"
"5","(-2425,3000)","0","mstr_discrete","I19";
;
CDS_SEC"1"
MATERIAL"FET"
VALUE"2N7002DW"
LOCATION"Q1L4"
PART_NUMBER"D24280-001"
ROOM"UART_MUX"
CDS_LOCATION"Q1L4"
SEC"1"
SEC_TYPE"SMLF"
CDS_LIB"mstr_discrete"
BOM_COST"DEBUG"
PACK_TYPE"SMLF";
"GATE <SIZE -1..0>"
$PN"2"11;
"SOURCE <SIZE-1..0>"
$PN"1"3;
"DRAIN <SIZE -1..0>"
$PN"6"14;
%"DIODE"
"1","(-6325,2750)","0","mstr_discrete","I2";
;
CDS_SEC"1"
VALUE"1N4148W"
MATERIAL"IC"
PACK_TYPE"SM"
PART_NUMBER"D89194-001"
LOCATION"CR1L1"
ROOM"UART_MUX"
CDS_LOCATION"CR1L1"
SEC"1"
BOM_COST"DEBUG"
CDS_LIB"mstr_discrete"
SEC_TYPE"SM";
"C"
$PN"1"15;
"A"
$PN"2"17;
%"RES"
"2","(-2425,3425)","0","mstr_discrete","I22";
;
CDS_SEC"1"
TOLERANCE"1%"
LOCATION"R1L38"
VALUE"1.00K"
WATTAGE"1/16W"
MATERIAL"CHIP"
PART_NUMBER"G21796-026"
PACK_TYPE"0402"
ROOM"UART_MUX"
CDS_LOCATION"R1L38"
SEC"1"
BOM_COST"DEBUG"
CDS_LIB"mstr_discrete"
SEC_TYPE"0402";
"A"
$PN"1"2;
"B"
$PN"2"14;
%"P3V3_STBY"
"1","(-2425,3625)","0","mstr_symbols","I24";
;
HDL_POWER"P3V3_STBY"
BODY_TYPE"PLUMBING"
SIZE"1B"
CDS_LIB"mstr_symbols"
VOLTAGE"3.3V";
"G\NAC"2;
%"GND"
"1","(-2425,2675)","0","mstr_symbols","I26";
;
HDL_POWER"GND"
BODY_TYPE"PLUMBING"
VOLTAGE"0.0V"
CDS_LIB"mstr_symbols"
SIZE"1B";
"A\NAC"3;
%"P3V3_STBY"
"1","(-3400,3250)","0","mstr_symbols","I29";
;
HDL_POWER"P3V3_STBY"
BODY_TYPE"PLUMBING"
VOLTAGE"3.3V"
CDS_LIB"mstr_symbols"
SIZE"1B";
"G\NAC"4;
%"DIODE"
"1","(-5675,2750)","0","mstr_discrete","I3";
;
CDS_SEC"1"
PART_NUMBER"D89194-001"
MATERIAL"IC"
LOCATION"CR1L2"
PACK_TYPE"SM"
VALUE"1N4148W"
ROOM"UART_MUX"
CDS_LOCATION"CR1L2"
SEC"1"
BOM_COST"DEBUG"
CDS_LIB"mstr_discrete"
SEC_TYPE"SM";
"C"
$PN"1"16;
"A"
$PN"2"15;
%"GND"
"1","(-3950,975)","0","mstr_symbols","I36";
;
HDL_POWER"GND"
BODY_TYPE"PLUMBING"
SIZE"1B"
CDS_LIB"mstr_symbols"
VOLTAGE"0.0V";
"A\NAC"5;
%"P3V3_STBY"
"1","(-3950,2375)","0","mstr_symbols","I38";
;
HDL_POWER"P3V3_STBY"
BODY_TYPE"PLUMBING"
SIZE"1B"
CDS_LIB"mstr_symbols"
VOLTAGE"3.3V";
"G\NAC"6;
%"DIODE"
"1","(-4975,2750)","0","mstr_discrete","I4";
;
CDS_SEC"1"
VALUE"1N4148W"
PACK_TYPE"SM"
PART_NUMBER"D89194-001"
LOCATION"CR1L3"
MATERIAL"IC"
ROOM"UART_MUX"
CDS_LOCATION"CR1L3"
SEC"1"
BOM_COST"DEBUG"
CDS_LIB"mstr_discrete"
SEC_TYPE"SM";
"C"
$PN"1"13;
"A"
$PN"2"16;
%"FET_N"
"8","(-1450,2650)","0","mstr_discrete","I43";
;
MATERIAL"FET"
PART_NUMBER"C79254-001"
LOCATION"Q6W4"
VALUE"2N7002"
CDS_LOCATION"Q6W4"
PACK_TYPE"SOT23LF"
ROOM"HOT_SWAP"
SEC_TYPE"SOT23LF"
SEC"1"
CDS_LIB"mstr_discrete"
CDS_SEC"1";
"GATE"
$PN"1"20;
"DRN"
$PN"3"14;
"SRC"
$PN"2"7;
%"GND"
"1","(-1450,2350)","0","mstr_symbols","I44";
;
HDL_POWER"GND"
BODY_TYPE"PLUMBING"
VOLTAGE"0.0V"
CDS_LIB"mstr_symbols"
SIZE"1B";
"A\NAC"7;
%"RES"
"2","(-3950,2100)","0","mstr_discrete","I46";
;
CDS_SEC"1"
MATERIAL"CHIP"
TOLERANCE"1%"
VALUE"1.00K"
WATTAGE"1/16W"
LOCATION"R6W16"
PACK_TYPE"0402"
PART_NUMBER"G21796-026"
SEC_TYPE"0402"
CDS_LIB"mstr_discrete"
BOM_COST"DEBUG"
SEC"1"
ROOM"UART_MUX"
CDS_LOCATION"R6W16";
"A"
$PN"1"6;
"B"
$PN"2"10;
%"NPN"
"1","(-4000,1450)","0","mstr_discrete","I47";
;
CDS_SEC"1"
VALUE"MMBT3904"
PART_NUMBER"C52245-001"
PACK_TYPE"SM"
MATERIAL"IC"
LOCATION"Q6W2"
ROOM"UART_MUX"
SEC"1"
BOM_COST"DEBUG"
CDS_LIB"mstr_discrete"
SEC_TYPE"SM"
CDS_LOCATION"Q6W2";
"C"
$PN"3"10;
"E"
$PN"2"5;
"B"
$PN"1"9;
%"RES"
"2","(-5950,1450)","1","mstr_discrete","I48";
;
CDS_SEC"1"
LOCATION"R6W49"
PART_NUMBER"G21796-133"
TOLERANCE"1%"
VALUE"40.2K"
PACK_TYPE"0402"
MATERIAL"CHIP"
WATTAGE"1/16W"
SEC_TYPE"0402"
SEC"1"
ROOM"HOT_SWAP"
CDS_LIB"mstr_discrete"
CDS_LOCATION"R6W49";
"A"
$PN"1"8;
"B"
$PN"2"9;
%"DIODE"
"1","(-4225,2750)","0","mstr_discrete","I5";
;
CDS_SEC"1"
PART_NUMBER"D89194-001"
LOCATION"CR1L4"
VALUE"1N4148W"
PACK_TYPE"SM"
MATERIAL"IC"
SEC_TYPE"SM"
CDS_LIB"mstr_discrete"
BOM_COST"DEBUG"
SEC"1"
CDS_LOCATION"CR1L4"
ROOM"UART_MUX";
"C"
$PN"1"12;
"A"
$PN"2"13;
%"RES"
"1","(-6975,2750)","0","mstr_discrete","I6";
;
CDS_SEC"1"
PACK_TYPE"0402"
TOLERANCE"5%"
VALUE"0.0"
PART_NUMBER"G21497-005"
LOCATION"R1L6"
MATERIAL"CHIP"
WATTAGE"1/16W"
ROOM"UART_MUX"
CDS_LOCATION"R1L6"
SEC"1"
BOM_COST"DEBUG"
CDS_LIB"mstr_discrete"
SEC_TYPE"0402";
"B"
$PN"2"17;
"A"
$PN"1"8;
%"NPN"
"1","(-3450,2750)","0","mstr_discrete","I8";
;
CDS_SEC"1"
PART_NUMBER"C52245-001"
PACK_TYPE"SM"
LOCATION"Q1L3"
VALUE"MMBT3904"
MATERIAL"IC"
ROOM"UART_MUX"
CDS_LOCATION"Q1L3"
SEC"1"
BOM_COST"DEBUG"
CDS_LIB"mstr_discrete"
SEC_TYPE"SM";
"C"
$PN"3"11;
"E"
$PN"2"1;
"B"
$PN"1"12;
END.
